(kicad_pcb
	(version 20260206)
	(generator "pcbnew")
	(generator_version "10.0")
	(general
		(thickness 1.6)
		(legacy_teardrops no)
	)
	(paper "A4")
	(title_block
		(title "fcb — Lightning_FCB_BRD.brd")
		(comment 1 "Lightning (Wiwynn / Facebook NVMe JBOF) / footprints 300-304 of 495")
	)
	(layers
		(0 "F.Cu" signal "TOP")
		(4 "In1.Cu" signal "L2GND")
		(6 "In2.Cu" signal "L3VCC")
		(2 "B.Cu" signal "BOTTOM")
		(9 "F.Adhes" user "F.Adhesive")
		(11 "B.Adhes" user "B.Adhesive")
		(13 "F.Paste" user "Package Geometry/Pastemask Top")
		(15 "B.Paste" user "Package Geometry/Pastemask Bottom")
		(5 "F.SilkS" user "Ref Des/Silkscreen Top")
		(7 "B.SilkS" user "Ref Des/Silkscreen Bottom")
		(1 "F.Mask" user "Board Geometry/Soldermask Top")
		(3 "B.Mask" user "Board Geometry/Soldermask Bottom")
		(17 "Dwgs.User" user "User.Drawings")
		(19 "Cmts.User" user "User.Comments")
		(21 "Eco1.User" user "User.Eco1")
		(23 "Eco2.User" user "User.Eco2")
		(25 "Edge.Cuts" user "Board Geometry/Outline")
		(27 "Margin" user)
		(31 "F.CrtYd" user "Package Geometry/Place Bound Top")
		(29 "B.CrtYd" user "Package Geometry/Place Bound Bottom")
		(35 "F.Fab" user "Ref Des/Assembly Top")
		(33 "B.Fab" user "Ref Des/Assembly Bottom")
	)
	(footprint ""
		(layer "F.Cu")
		(at 7.3152 -78.5114)
		(property "Reference" "Q4"
			(at 0 0 0)
			(layer "F.SilkS")
			(hide yes)
			(effects
				(font
					(size 1.27 1.27)
				)
			)
		)
		(property "Value" "PMBS3904-1-GP"
			(at 0 -9.0932 0)
			(unlocked yes)
			(layer "F.Fab")
			(hide yes)
			(effects
				(font
					(size 1.016 1.016)
					(thickness 0.1524)
				)
			)
		)
		(property "Device Type" "SOT-23-10H44"
			(at 0 -10.6172 0)
			(unlocked yes)
			(layer "F.Fab")
			(hide yes)
			(effects
				(font
					(size 1.016 1.016)
					(thickness 0.1524)
				)
			)
		)
		(duplicate_pad_numbers_are_jumpers no)
		(fp_line
			(start -1.7526 1.8796)
			(end -1.7526 0.9906)
			(stroke
				(width 0.3302)
				(type default)
			)
			(layer "F.SilkS")
		)
		(fp_line
			(start -1.651 -1.778)
			(end -1.651 1.778)
			(stroke
				(width 0.1524)
				(type default)
			)
			(layer "F.SilkS")
		)
		(fp_line
			(start -1.651 1.778)
			(end 1.651 1.778)
			(stroke
				(width 0.1524)
				(type default)
			)
			(layer "F.SilkS")
		)
		(fp_line
			(start -1.279398 2.152142)
			(end -0.9906 1.86309)
			(stroke
				(width 0.0127)
				(type default)
			)
			(layer "F.SilkS")
		)
		(fp_line
			(start -1.279144 2.15265)
			(end -0.701294 2.15265)
			(stroke
				(width 0.0127)
				(type default)
			)
			(layer "F.SilkS")
		)
		(fp_line
			(start -1.260856 2.1336)
			(end -0.720344 2.1336)
			(stroke
				(width 0.0127)
				(type default)
			)
			(layer "F.SilkS")
		)
		(fp_line
			(start -1.251458 2.124202)
			(end -0.729996 2.124202)
			(stroke
				(width 0.0127)
				(type default)
			)
			(layer "F.SilkS")
		)
		(fp_line
			(start -1.241806 2.11455)
			(end -0.739394 2.11455)
			(stroke
				(width 0.0127)
				(type default)
			)
			(layer "F.SilkS")
		)
		(fp_line
			(start -1.232408 2.105152)
			(end -0.749046 2.105152)
			(stroke
				(width 0.0127)
				(type default)
			)
			(layer "F.SilkS")
		)
		(fp_line
			(start -1.222756 2.0955)
			(end -0.758444 2.0955)
			(stroke
				(width 0.0127)
				(type default)
			)
			(layer "F.SilkS")
		)
		(fp_line
			(start -1.213358 2.086102)
			(end -0.768096 2.086102)
			(stroke
				(width 0.0127)
				(type default)
			)
			(layer "F.SilkS")
		)
		(fp_line
			(start -1.203706 2.07645)
			(end -0.777494 2.07645)
			(stroke
				(width 0.0127)
				(type default)
			)
			(layer "F.SilkS")
		)
		(fp_line
			(start -1.194308 2.067052)
			(end -0.787146 2.067052)
			(stroke
				(width 0.0127)
				(type default)
			)
			(layer "F.SilkS")
		)
		(fp_line
			(start -1.184656 2.0574)
			(end -0.796544 2.0574)
			(stroke
				(width 0.0127)
				(type default)
			)
			(layer "F.SilkS")
		)
		(fp_line
			(start -1.175258 2.048002)
			(end -0.806196 2.048002)
			(stroke
				(width 0.0127)
				(type default)
			)
			(layer "F.SilkS")
		)
		(fp_line
			(start -1.165606 2.03835)
			(end -0.815594 2.03835)
			(stroke
				(width 0.0127)
				(type default)
			)
			(layer "F.SilkS")
		)
		(fp_line
			(start -1.156208 2.028952)
			(end -0.825246 2.028952)
			(stroke
				(width 0.0127)
				(type default)
			)
			(layer "F.SilkS")
		)
		(fp_line
			(start -1.146556 2.0193)
			(end -0.834644 2.0193)
			(stroke
				(width 0.0127)
				(type default)
			)
			(layer "F.SilkS")
		)
		(fp_line
			(start -1.137158 2.009902)
			(end -0.844296 2.009902)
			(stroke
				(width 0.0127)
				(type default)
			)
			(layer "F.SilkS")
		)
		(fp_line
			(start -1.127506 2.00025)
			(end -0.853694 2.00025)
			(stroke
				(width 0.0127)
				(type default)
			)
			(layer "F.SilkS")
		)
		(fp_line
			(start -1.118108 1.990852)
			(end -0.863346 1.990852)
			(stroke
				(width 0.0127)
				(type default)
			)
			(layer "F.SilkS")
		)
		(fp_line
			(start -1.108456 1.9812)
			(end -0.872744 1.9812)
			(stroke
				(width 0.0127)
				(type default)
			)
			(layer "F.SilkS")
		)
		(fp_line
			(start -1.099058 1.971802)
			(end -0.882396 1.971802)
			(stroke
				(width 0.0127)
				(type default)
			)
			(layer "F.SilkS")
		)
		(fp_line
			(start -1.089406 1.96215)
			(end -0.891794 1.96215)
			(stroke
				(width 0.0127)
				(type default)
			)
			(layer "F.SilkS")
		)
		(fp_line
			(start -1.080008 1.952752)
			(end -0.901446 1.952752)
			(stroke
				(width 0.0127)
				(type default)
			)
			(layer "F.SilkS")
		)
		(fp_line
			(start -1.070356 1.9431)
			(end -0.910844 1.9431)
			(stroke
				(width 0.0127)
				(type default)
			)
			(layer "F.SilkS")
		)
		(fp_line
			(start -1.060958 1.933702)
			(end -0.920496 1.933702)
			(stroke
				(width 0.0127)
				(type default)
			)
			(layer "F.SilkS")
		)
		(fp_line
			(start -1.051306 1.92405)
			(end -0.929894 1.92405)
			(stroke
				(width 0.0127)
				(type default)
			)
			(layer "F.SilkS")
		)
		(fp_line
			(start -1.041908 1.914652)
			(end -0.939546 1.914652)
			(stroke
				(width 0.0127)
				(type default)
			)
			(layer "F.SilkS")
		)
		(fp_line
			(start -1.032256 1.905)
			(end -0.948944 1.905)
			(stroke
				(width 0.0127)
				(type default)
			)
			(layer "F.SilkS")
		)
		(fp_line
			(start -1.022858 1.895602)
			(end -0.958596 1.895602)
			(stroke
				(width 0.0127)
				(type default)
			)
			(layer "F.SilkS")
		)
		(fp_line
			(start -1.013206 1.88595)
			(end -0.967994 1.88595)
			(stroke
				(width 0.0127)
				(type default)
			)
			(layer "F.SilkS")
		)
		(fp_line
			(start -1.003808 1.876552)
			(end -0.977646 1.876552)
			(stroke
				(width 0.0127)
				(type default)
			)
			(layer "F.SilkS")
		)
		(fp_line
			(start -0.994156 1.8669)
			(end -0.987044 1.8669)
			(stroke
				(width 0.0127)
				(type default)
			)
			(layer "F.SilkS")
		)
		(fp_line
			(start -0.9906 1.86309)
			(end -0.701294 2.15265)
			(stroke
				(width 0.0127)
				(type default)
			)
			(layer "F.SilkS")
		)
		(fp_line
			(start -0.719074 2.145538)
			(end -1.265936 2.14122)
			(stroke
				(width 0.0127)
				(type default)
			)
			(layer "F.SilkS")
		)
		(fp_line
			(start -0.71628 2.15265)
			(end -1.26492 2.15265)
			(stroke
				(width 0.0127)
				(type default)
			)
			(layer "F.SilkS")
		)
		(fp_line
			(start -0.635 1.8796)
			(end -1.7526 1.8796)
			(stroke
				(width 0.3302)
				(type default)
			)
			(layer "F.SilkS")
		)
		(fp_line
			(start 1.651 -1.778)
			(end -1.651 -1.778)
			(stroke
				(width 0.1524)
				(type default)
			)
			(layer "F.SilkS")
		)
		(fp_line
			(start 1.651 1.778)
			(end 1.651 -1.778)
			(stroke
				(width 0.1524)
				(type default)
			)
			(layer "F.SilkS")
		)
		(fp_poly
			(pts
				(xy -1.285748 2.159) (xy -1.285748 1.8796) (xy -1.778 1.8796) (xy -1.778 -1.8796) (xy 1.778 -1.8796)
				(xy 1.778 1.8796) (xy -0.694944 1.8796) (xy -0.694944 2.159)
			)
			(stroke
				(width 0)
				(type default)
			)
			(fill no)
			(layer "F.CrtYd")
		)
		(fp_poly
			(pts
				(xy -1.285748 2.159) (xy -1.285748 1.8796) (xy -1.778 1.8796) (xy -1.778 -1.8796) (xy 1.778 -1.8796)
				(xy 1.778 1.8796) (xy -0.694944 1.8796) (xy -0.694944 2.159)
			)
			(stroke
				(width 0)
				(type default)
			)
			(fill no)
			(layer "F.Fab")
		)
		(pad "1" smd rect
			(at -0.98425 0.9525)
			(size 0.762 1.143)
			(layers "F.Cu" "F.Mask" "F.Paste")
			(net "LED_DR_LED4_B")
		)
		(pad "2" smd rect
			(at 0.98425 0.9525)
			(size 0.762 1.143)
			(layers "F.Cu" "F.Mask" "F.Paste")
			(net "GND")
		)
		(pad "3" smd rect
			(at 0 -0.9525)
			(size 0.762 1.143)
			(layers "F.Cu" "F.Mask" "F.Paste")
			(net "LED_DR_LED4_BLUE")
		)
	)
	(footprint ""
		(layer "F.Cu")
		(at 43.3324 -134.8232)
		(property "Reference" "PR96"
			(at 0 0 0)
			(layer "F.SilkS")
			(hide yes)
			(effects
				(font
					(size 1.27 1.27)
				)
			)
		)
		(property "Value" "0R2J-2-GP"
			(at 0.064008 -3.993896 0)
			(unlocked yes)
			(layer "F.Fab")
			(hide yes)
			(effects
				(font
					(size 1.016 1.016)
					(thickness 0.1524)
				)
			)
		)
		(property "Device Type" "R402H16"
			(at 0.064008 -5.517896 0)
			(unlocked yes)
			(layer "F.Fab")
			(hide yes)
			(effects
				(font
					(size 1.016 1.016)
					(thickness 0.1524)
				)
			)
		)
		(duplicate_pad_numbers_are_jumpers no)
		(fp_line
			(start -0.508 -0.9398)
			(end -0.508 0.9398)
			(stroke
				(width 0.1524)
				(type default)
			)
			(layer "F.SilkS")
		)
		(fp_line
			(start 0.508 -0.9398)
			(end -0.508 -0.9398)
			(stroke
				(width 0.1524)
				(type default)
			)
			(layer "F.SilkS")
		)
		(fp_rect
			(start -0.508 0.9398)
			(end 0.508 -0.9398)
			(stroke
				(width 0)
				(type default)
			)
			(fill no)
			(layer "F.CrtYd")
		)
		(fp_rect
			(start -0.508 0.9398)
			(end 0.508 -0.9398)
			(stroke
				(width 0)
				(type default)
			)
			(fill no)
			(layer "F.Fab")
		)
		(pad "1" smd custom
			(at 0 -0.4445)
			(size 0.1397 0.1397)
			(layers "F.Cu" "F.Mask" "F.Paste")
			(net "P12VL_2490_VCC")
			(options
				(clearance outline)
				(anchor circle)
			)
			(primitives
				(gr_poly
					(pts
						(arc
							(start -0.1778 -0.2794)
							(mid -0.249642 -0.249642)
							(end -0.2794 -0.1778)
						)
						(arc
							(start -0.2794 0.1778)
							(mid -0.249642 0.249642)
							(end -0.1778 0.2794)
						)
						(arc
							(start 0.1778 0.2794)
							(mid 0.249642 0.249642)
							(end 0.2794 0.1778)
						)
						(arc
							(start 0.2794 -0.1778)
							(mid 0.249642 -0.249642)
							(end 0.1778 -0.2794)
						)
					)
					(width 0)
					(fill yes)
				)
			)
		)
		(pad "2" smd custom
			(at 0 0.4445)
			(size 0.1397 0.1397)
			(layers "F.Cu" "F.Mask" "F.Paste")
			(net "P12V")
			(options
				(clearance outline)
				(anchor circle)
			)
			(primitives
				(gr_poly
					(pts
						(arc
							(start -0.1778 -0.2794)
							(mid -0.249642 -0.249642)
							(end -0.2794 -0.1778)
						)
						(arc
							(start -0.2794 0.1778)
							(mid -0.249642 0.249642)
							(end -0.1778 0.2794)
						)
						(arc
							(start 0.1778 0.2794)
							(mid 0.249642 0.249642)
							(end 0.2794 0.1778)
						)
						(arc
							(start 0.2794 -0.1778)
							(mid 0.249642 -0.249642)
							(end 0.1778 -0.2794)
						)
					)
					(width 0)
					(fill yes)
				)
			)
		)
	)
	(footprint ""
		(layer "F.Cu")
		(at 19.939 -18.161 90)
		(property "Reference" "R71"
			(at 0 0 90)
			(layer "F.SilkS")
			(hide yes)
			(effects
				(font
					(size 1.27 1.27)
				)
			)
		)
		(property "Value" "27KR3F-GP"
			(at -0.0254 -2.5146 90)
			(unlocked yes)
			(layer "F.Fab")
			(hide yes)
			(effects
				(font
					(size 1.016 1.016)
					(thickness 0.1524)
				)
			)
		)
		(property "Device Type" "R603H22"
			(at -0.0254 -4.0386 90)
			(unlocked yes)
			(layer "F.Fab")
			(hide yes)
			(effects
				(font
					(size 1.016 1.016)
					(thickness 0.1524)
				)
			)
		)
		(duplicate_pad_numbers_are_jumpers no)
		(fp_line
			(start 0.2032 0)
			(end 0.4826 0)
			(stroke
				(width 0.2032)
				(type default)
			)
			(layer "F.SilkS")
		)
		(fp_line
			(start -0.4826 0)
			(end -0.2032 0)
			(stroke
				(width 0.2032)
				(type default)
			)
			(layer "F.SilkS")
		)
		(fp_rect
			(start -0.5842 1.3335)
			(end 0.5842 -1.3335)
			(stroke
				(width 0)
				(type default)
			)
			(fill no)
			(layer "F.CrtYd")
		)
		(fp_rect
			(start -0.5842 1.3335)
			(end 0.5842 -1.3335)
			(stroke
				(width 0)
				(type default)
			)
			(fill no)
			(layer "F.Fab")
		)
		(pad "1" smd custom
			(at 0 -0.762 90)
			(size 0.2159 0.2159)
			(layers "F.Cu" "F.Mask" "F.Paste")
			(net "FAN_TACH12")
			(options
				(clearance outline)
				(anchor circle)
			)
			(primitives
				(gr_poly
					(pts
						(arc
							(start -0.3302 -0.4318)
							(mid -0.402042 -0.402042)
							(end -0.4318 -0.3302)
						)
						(arc
							(start -0.4318 0.3302)
							(mid -0.402042 0.402042)
							(end -0.3302 0.4318)
						)
						(arc
							(start 0.3302 0.4318)
							(mid 0.402042 0.402042)
							(end 0.4318 0.3302)
						)
						(arc
							(start 0.4318 -0.3302)
							(mid 0.402042 -0.402042)
							(end 0.3302 -0.4318)
						)
					)
					(width 0)
					(fill yes)
				)
			)
		)
		(pad "2" smd custom
			(at 0 0.762 90)
			(size 0.2159 0.2159)
			(layers "F.Cu" "F.Mask" "F.Paste")
			(net "FANIN_12")
			(options
				(clearance outline)
				(anchor circle)
			)
			(primitives
				(gr_poly
					(pts
						(arc
							(start -0.3302 -0.4318)
							(mid -0.402042 -0.402042)
							(end -0.4318 -0.3302)
						)
						(arc
							(start -0.4318 0.3302)
							(mid -0.402042 0.402042)
							(end -0.3302 0.4318)
						)
						(arc
							(start 0.3302 0.4318)
							(mid 0.402042 0.402042)
							(end 0.4318 0.3302)
						)
						(arc
							(start 0.4318 -0.3302)
							(mid 0.402042 -0.402042)
							(end 0.3302 -0.4318)
						)
					)
					(width 0)
					(fill yes)
				)
			)
		)
	)
	(footprint ""
		(layer "F.Cu")
		(at 15.5956 -171.4754)
		(property "Reference" "R52"
			(at 0 0 0)
			(layer "F.SilkS")
			(hide yes)
			(effects
				(font
					(size 1.27 1.27)
				)
			)
		)
		(property "Value" "4K7R2F-GP"
			(at 0.064008 -3.993896 0)
			(unlocked yes)
			(layer "F.Fab")
			(hide yes)
			(effects
				(font
					(size 1.016 1.016)
					(thickness 0.1524)
				)
			)
		)
		(property "Device Type" "R402H16"
			(at 0.064008 -5.517896 0)
			(unlocked yes)
			(layer "F.Fab")
			(hide yes)
			(effects
				(font
					(size 1.016 1.016)
					(thickness 0.1524)
				)
			)
		)
		(duplicate_pad_numbers_are_jumpers no)
		(fp_line
			(start -0.508 -0.9398)
			(end -0.508 0.9398)
			(stroke
				(width 0.1524)
				(type default)
			)
			(layer "F.SilkS")
		)
		(fp_line
			(start 0.508 -0.9398)
			(end -0.508 -0.9398)
			(stroke
				(width 0.1524)
				(type default)
			)
			(layer "F.SilkS")
		)
		(fp_rect
			(start -0.508 0.9398)
			(end 0.508 -0.9398)
			(stroke
				(width 0)
				(type default)
			)
			(fill no)
			(layer "F.CrtYd")
		)
		(fp_rect
			(start -0.508 0.9398)
			(end 0.508 -0.9398)
			(stroke
				(width 0)
				(type default)
			)
			(fill no)
			(layer "F.Fab")
		)
		(pad "1" smd custom
			(at 0 -0.4445)
			(size 0.1397 0.1397)
			(layers "F.Cu" "F.Mask" "F.Paste")
			(net "P3V3")
			(options
				(clearance outline)
				(anchor circle)
			)
			(primitives
				(gr_poly
					(pts
						(arc
							(start -0.1778 -0.2794)
							(mid -0.249642 -0.249642)
							(end -0.2794 -0.1778)
						)
						(arc
							(start -0.2794 0.1778)
							(mid -0.249642 0.249642)
							(end -0.1778 0.2794)
						)
						(arc
							(start 0.1778 0.2794)
							(mid 0.249642 0.249642)
							(end 0.2794 0.1778)
						)
						(arc
							(start 0.2794 -0.1778)
							(mid 0.249642 -0.249642)
							(end 0.1778 -0.2794)
						)
					)
					(width 0)
					(fill yes)
				)
			)
		)
		(pad "2" smd custom
			(at 0 0.4445)
			(size 0.1397 0.1397)
			(layers "F.Cu" "F.Mask" "F.Paste")
			(net "SEB_PEER_2A_2B_HB_OUT")
			(options
				(clearance outline)
				(anchor circle)
			)
			(primitives
				(gr_poly
					(pts
						(arc
							(start -0.1778 -0.2794)
							(mid -0.249642 -0.249642)
							(end -0.2794 -0.1778)
						)
						(arc
							(start -0.2794 0.1778)
							(mid -0.249642 0.249642)
							(end -0.1778 0.2794)
						)
						(arc
							(start 0.1778 0.2794)
							(mid 0.249642 0.249642)
							(end 0.2794 0.1778)
						)
						(arc
							(start 0.2794 -0.1778)
							(mid 0.249642 -0.249642)
							(end 0.1778 -0.2794)
						)
					)
					(width 0)
					(fill yes)
				)
			)
		)
	)
	(footprint ""
		(layer "F.Cu")
		(at 23.1902 -145.161 180)
		(property "Reference" "PR112"
			(at 0 0 180)
			(layer "F.SilkS")
			(hide yes)
			(effects
				(font
					(size 1.27 1.27)
				)
			)
		)
		(property "Value" "6K81R2F-1-GP"
			(at 0.064008 -3.993896 180)
			(unlocked yes)
			(layer "F.Fab")
			(hide yes)
			(effects
				(font
					(size 1.016 1.016)
					(thickness 0.1524)
				)
			)
		)
		(property "Device Type" "R402H16"
			(at 0.064008 -5.517896 180)
			(unlocked yes)
			(layer "F.Fab")
			(hide yes)
			(effects
				(font
					(size 1.016 1.016)
					(thickness 0.1524)
				)
			)
		)
		(duplicate_pad_numbers_are_jumpers no)
		(fp_line
			(start 0.508 -0.9398)
			(end -0.508 -0.9398)
			(stroke
				(width 0.1524)
				(type default)
			)
			(layer "F.SilkS")
		)
		(fp_line
			(start -0.508 -0.9398)
			(end -0.508 0.9398)
			(stroke
				(width 0.1524)
				(type default)
			)
			(layer "F.SilkS")
		)
		(fp_rect
			(start -0.508 0.9398)
			(end 0.508 -0.9398)
			(stroke
				(width 0)
				(type default)
			)
			(fill no)
			(layer "F.CrtYd")
		)
		(fp_rect
			(start -0.508 0.9398)
			(end 0.508 -0.9398)
			(stroke
				(width 0)
				(type default)
			)
			(fill no)
			(layer "F.Fab")
		)
		(pad "1" smd custom
			(at 0 -0.4445 180)
			(size 0.1397 0.1397)
			(layers "F.Cu" "F.Mask" "F.Paste")
			(net "P12VU_2490_EN_2")
			(options
				(clearance outline)
				(anchor circle)
			)
			(primitives
				(gr_poly
					(pts
						(arc
							(start -0.1778 -0.2794)
							(mid -0.249642 -0.249642)
							(end -0.2794 -0.1778)
						)
						(arc
							(start -0.2794 0.1778)
							(mid -0.249642 0.249642)
							(end -0.1778 0.2794)
						)
						(arc
							(start 0.1778 0.2794)
							(mid 0.249642 0.249642)
							(end 0.2794 0.1778)
						)
						(arc
							(start 0.2794 -0.1778)
							(mid 0.249642 -0.249642)
							(end 0.1778 -0.2794)
						)
					)
					(width 0)
					(fill yes)
				)
			)
		)
		(pad "2" smd custom
			(at 0 0.4445 180)
			(size 0.1397 0.1397)
			(layers "F.Cu" "F.Mask" "F.Paste")
			(net "GND")
			(options
				(clearance outline)
				(anchor circle)
			)
			(primitives
				(gr_poly
					(pts
						(arc
							(start -0.1778 -0.2794)
							(mid -0.249642 -0.249642)
							(end -0.2794 -0.1778)
						)
						(arc
							(start -0.2794 0.1778)
							(mid -0.249642 0.249642)
							(end -0.1778 0.2794)
						)
						(arc
							(start 0.1778 0.2794)
							(mid 0.249642 0.249642)
							(end 0.2794 0.1778)
						)
						(arc
							(start 0.2794 -0.1778)
							(mid 0.249642 -0.249642)
							(end 0.1778 -0.2794)
						)
					)
					(width 0)
					(fill yes)
				)
			)
		)
	)
)
